# S9S_MB_2U (Grand Teton) — schematic netlist excerpt (pin names and nets, part order shuffled) for the footprints in the layout excerpt that follows; sources: Cadence DE-HDL packaged netlist, KiCad conversion of 03242023_DA0F0TMBIJ0_F0T_Motherboard_J_brd_V01_OCP.brd

R4624  Q_RES  0 5% CHIP  pkg 0402LF  page 248 : A = JTAG_BMC_SW_OE ; B = JTAG_BMC_SW_R_OE

PU74  NB682GDZ  NB682GD-Z IC  pkg QFN13_2X3  page 263
  VIN  = SW_P1V8_PCH_AUX_FLT
  PGND  = GND
  C1  = P1V8_PCH_AUX_VCC
  C0  = GND
  EN  = FM_PCH_P1V8_AUX_EN_R
  \lp#\  = P1V8_PCH_AUX_VCC
  MODE  = P1V8_PCH_AUX_MODE
  SW  = SW_P1V8_PCH_AUX_SW
  BST  = SW_P1V8_PCH_AUX_BST
  \3v3\  = P1V8_PCH_AUX_VCC
  AGND  = GND
  VOUT  = P1V8_PCH_AUX
  PG  = PWRGD_P1V8_PCH_AUX_R

(kicad_pcb
	(version 20260206)
	(generator "pcbnew")
	(generator_version "10.0")
	(general
		(thickness 1.6)
		(legacy_teardrops no)
	)
	(paper "A4")
	(title_block
		(title "03242023_DA0F0TMBIJ0_F0T_Motherboard_J_brd_V01_OCP.brd")
		(comment 1 "Grand Teton / footprints 1934-1935 of 6105")
	)
	(layers
		(0 "F.Cu" signal "TOP")
		(4 "In1.Cu" signal "GND")
		(6 "In2.Cu" signal "IN1")
		(8 "In3.Cu" signal "GND1")
		(10 "In4.Cu" signal "IN2")
		(12 "In5.Cu" signal "GND2")
		(14 "In6.Cu" signal "IN3")
		(16 "In7.Cu" signal "GND3")
		(18 "In8.Cu" signal "VCC")
		(20 "In9.Cu" signal "VCC1")
		(22 "In10.Cu" signal "GND4")
		(24 "In11.Cu" signal "IN4")
		(26 "In12.Cu" signal "GND5")
		(28 "In13.Cu" signal "IN5")
		(30 "In14.Cu" signal "GND6")
		(32 "In15.Cu" signal "IN6")
		(34 "In16.Cu" signal "GND7")
		(2 "B.Cu" signal "BOTTOM")
		(9 "F.Adhes" user "F.Adhesive")
		(11 "B.Adhes" user "B.Adhesive")
		(13 "F.Paste" user "Package Geometry/Pastemask Top")
		(15 "B.Paste" user "Package Geometry/Pastemask Bottom")
		(5 "F.SilkS" user "Ref Des/Silkscreen Top")
		(7 "B.SilkS" user "Ref Des/Silkscreen Bottom")
		(1 "F.Mask" user "Board Geometry/Soldermask Top")
		(3 "B.Mask" user "Board Geometry/Soldermask Bottom")
		(17 "Dwgs.User" user "User.Drawings")
		(19 "Cmts.User" user "User.Comments")
		(21 "Eco1.User" user "User.Eco1")
		(23 "Eco2.User" user "User.Eco2")
		(25 "Edge.Cuts" user "Board Geometry/Outline")
		(27 "Margin" user)
		(31 "F.CrtYd" user "Package Geometry/Place Bound Top")
		(29 "B.CrtYd" user "Package Geometry/Place Bound Bottom")
		(35 "F.Fab" user "Ref Des/Assembly Top")
		(33 "B.Fab" user "Ref Des/Assembly Bottom")
	)
	(footprint ""
		(layer "F.Cu")
		(at 122.809 -60.035948 -90)
		(property "Reference" "R4624"
			(at 0 0 270)
			(layer "F.SilkS")
			(hide yes)
			(effects
				(font
					(size 1.27 1.27)
				)
			)
		)
		(property "Value" ""
			(at 0 0 270)
			(layer "F.Fab")
			(effects
				(font
					(size 1.27 1.27)
				)
			)
		)
		(duplicate_pad_numbers_are_jumpers no)
		(fp_line
			(start -0.7874 0.4064)
			(end -0.7874 -0.4064)
			(stroke
				(width 0.1524)
				(type default)
			)
			(layer "F.SilkS")
		)
		(fp_line
			(start 0.7874 0.4064)
			(end -0.7874 0.4064)
			(stroke
				(width 0.1524)
				(type default)
			)
			(layer "F.SilkS")
		)
		(fp_line
			(start -0.7874 -0.4064)
			(end 0.7874 -0.4064)
			(stroke
				(width 0.1524)
				(type default)
			)
			(layer "F.SilkS")
		)
		(fp_line
			(start 0.7874 -0.4064)
			(end 0.7874 0.4064)
			(stroke
				(width 0.1524)
				(type default)
			)
			(layer "F.SilkS")
		)
		(fp_line
			(start -0.67945 0.3048)
			(end -0.67945 -0.305054)
			(stroke
				(width 0.1)
				(type default)
			)
			(layer "F.Fab")
		)
		(fp_line
			(start -0.12065 0.3048)
			(end -0.67945 0.3048)
			(stroke
				(width 0.1)
				(type default)
			)
			(layer "F.Fab")
		)
		(fp_line
			(start 0.120396 0.3048)
			(end 0.120396 0.2794)
			(stroke
				(width 0.1)
				(type default)
			)
			(layer "F.Fab")
		)
		(fp_line
			(start 0.67945 0.3048)
			(end 0.120396 0.3048)
			(stroke
				(width 0.1)
				(type default)
			)
			(layer "F.Fab")
		)
		(fp_line
			(start -0.12065 0.2794)
			(end -0.12065 0.3048)
			(stroke
				(width 0.1)
				(type default)
			)
			(layer "F.Fab")
		)
		(fp_line
			(start 0.120396 0.2794)
			(end -0.12065 0.2794)
			(stroke
				(width 0.1)
				(type default)
			)
			(layer "F.Fab")
		)
		(fp_line
			(start -0.12065 -0.2794)
			(end 0.12065 -0.2794)
			(stroke
				(width 0.1)
				(type default)
			)
			(layer "F.Fab")
		)
		(fp_line
			(start 0.12065 -0.2794)
			(end 0.12065 -0.3048)
			(stroke
				(width 0.1)
				(type default)
			)
			(layer "F.Fab")
		)
		(fp_line
			(start 0.12065 -0.3048)
			(end 0.67945 -0.3048)
			(stroke
				(width 0.1)
				(type default)
			)
			(layer "F.Fab")
		)
		(fp_line
			(start 0.67945 -0.3048)
			(end 0.67945 0.3048)
			(stroke
				(width 0.1)
				(type default)
			)
			(layer "F.Fab")
		)
		(fp_line
			(start -0.67945 -0.305054)
			(end -0.12065 -0.305054)
			(stroke
				(width 0.1)
				(type default)
			)
			(layer "F.Fab")
		)
		(fp_line
			(start -0.12065 -0.305054)
			(end -0.12065 -0.2794)
			(stroke
				(width 0.1)
				(type default)
			)
			(layer "F.Fab")
		)
		(pad "1" smd circle
			(at -0.40005 0 270)
			(size 0 0)
			(layers "F.Cu" "F.Mask" "F.Paste")
			(net "JTAG_BMC_SW_OE")
		)
		(pad "2" smd circle
			(at 0.40005 0 270)
			(size 0 0)
			(layers "F.Cu" "F.Mask" "F.Paste")
			(net "JTAG_BMC_SW_R_OE")
		)
	)
	(footprint ""
		(layer "F.Cu")
		(at 384.359912 -76.14412 180)
		(property "Reference" "PU74"
			(at -2.749042 -2.999232 0)
			(unlocked yes)
			(layer "F.SilkS")
			(effects
				(font
					(size 0.7874 0.5842)
					(thickness 0.1524)
				)
				(justify left)
			)
		)
		(property "Value" ""
			(at 0 0 180)
			(layer "F.Fab")
			(effects
				(font
					(size 1.27 1.27)
				)
			)
		)
		(duplicate_pad_numbers_are_jumpers no)
		(fp_line
			(start 1.050036 1.549908)
			(end 1.050036 0.762)
			(stroke
				(width 0.1524)
				(type default)
			)
			(layer "F.SilkS")
		)
		(fp_line
			(start 1.050036 -0.762)
			(end 1.050036 -1.549908)
			(stroke
				(width 0.1524)
				(type default)
			)
			(layer "F.SilkS")
		)
		(fp_line
			(start 1.050036 -1.549908)
			(end 1.016 -1.549908)
			(stroke
				(width 0.1524)
				(type default)
			)
			(layer "F.SilkS")
		)
		(fp_line
			(start 1.016 1.549908)
			(end 1.050036 1.549908)
			(stroke
				(width 0.1524)
				(type default)
			)
			(layer "F.SilkS")
		)
		(fp_line
			(start -1.016 -1.549908)
			(end -1.050036 -1.549908)
			(stroke
				(width 0.1524)
				(type default)
			)
			(layer "F.SilkS")
		)
		(fp_line
			(start -1.050036 1.549908)
			(end -1.016 1.549908)
			(stroke
				(width 0.1524)
				(type default)
			)
			(layer "F.SilkS")
		)
		(fp_line
			(start -1.050036 0.762)
			(end -1.050036 1.549908)
			(stroke
				(width 0.1524)
				(type default)
			)
			(layer "F.SilkS")
		)
		(fp_line
			(start -1.050036 -0.2286)
			(end -1.050036 0.2286)
			(stroke
				(width 0.1524)
				(type default)
			)
			(layer "F.SilkS")
		)
		(fp_line
			(start -1.050036 -1.549908)
			(end -1.050036 -0.762)
			(stroke
				(width 0.1524)
				(type default)
			)
			(layer "F.SilkS")
		)
		(fp_poly
			(pts
				(xy -1.446022 -0.736854) (xy -1.913382 -0.89281) (xy -1.601724 -1.204468)
			)
			(stroke
				(width 0)
				(type default)
			)
			(fill yes)
			(layer "F.SilkS")
		)
		(fp_line
			(start 1.050036 1.549908)
			(end 1.050036 -1.549908)
			(stroke
				(width 0.1)
				(type default)
			)
			(layer "F.Fab")
		)
		(fp_line
			(start 1.050036 -1.549908)
			(end -1.050036 -1.549908)
			(stroke
				(width 0.1)
				(type default)
			)
			(layer "F.Fab")
		)
		(fp_line
			(start -1.050036 1.549908)
			(end 1.050036 1.549908)
			(stroke
				(width 0.1)
				(type default)
			)
			(layer "F.Fab")
		)
		(fp_line
			(start -1.050036 -1.549908)
			(end -1.050036 1.549908)
			(stroke
				(width 0.1)
				(type default)
			)
			(layer "F.Fab")
		)
		(fp_poly
			(pts
				(xy -1.851914 -0.720344) (xy -1.411224 -0.499872) (xy -1.851914 -0.279654)
			)
			(stroke
				(width 0)
				(type default)
			)
			(fill yes)
			(layer "F.Fab")
		)
		(pad "1" smd rect
			(at -0.54991 -0.499872 270)
			(size 0.254 1.4986)
			(layers "F.Cu" "F.Mask" "F.Paste")
			(net "SW_P1V8_PCH_AUX_FLT")
		)
		(pad "2" smd rect
			(at -0.54991 0.499872 270)
			(size 0.254 1.4986)
			(layers "F.Cu" "F.Mask" "F.Paste")
			(net "GND")
		)
		(pad "3" smd rect
			(at -0.750062 1.450086 180)
			(size 0.254 0.7112)
			(layers "F.Cu" "F.Mask" "F.Paste")
			(net "P1V8_PCH_AUX_VCC")
		)
		(pad "4" smd rect
			(at -0.249936 1.450086 180)
			(size 0.254 0.7112)
			(layers "F.Cu" "F.Mask" "F.Paste")
			(net "GND")
		)
		(pad "5" smd rect
			(at 0.249936 1.450086 180)
			(size 0.254 0.7112)
			(layers "F.Cu" "F.Mask" "F.Paste")
			(net "FM_PCH_P1V8_AUX_EN_R")
		)
		(pad "6" smd rect
			(at 0.750062 1.450086 180)
			(size 0.254 0.7112)
			(layers "F.Cu" "F.Mask" "F.Paste")
			(net "P1V8_PCH_AUX_VCC")
		)
		(pad "7" smd rect
			(at 0.94996 0.499872 270)
			(size 0.254 0.7112)
			(layers "F.Cu" "F.Mask" "F.Paste")
			(net "P1V8_PCH_AUX_MODE")
		)
		(pad "8" smd rect
			(at 0.54991 0 270)
			(size 0.254 1.4986)
			(layers "F.Cu" "F.Mask" "F.Paste")
			(net "SW_P1V8_PCH_AUX_SW")
		)
		(pad "9" smd rect
			(at 0.94996 -0.499872 270)
			(size 0.254 0.7112)
			(layers "F.Cu" "F.Mask" "F.Paste")
			(net "SW_P1V8_PCH_AUX_BST")
		)
		(pad "10" smd rect
			(at 0.750062 -1.450086 180)
			(size 0.254 0.7112)
			(layers "F.Cu" "F.Mask" "F.Paste")
			(net "P1V8_PCH_AUX_VCC")
		)
		(pad "11" smd rect
			(at 0.249936 -1.450086 180)
			(size 0.254 0.7112)
			(layers "F.Cu" "F.Mask" "F.Paste")
			(net "GND")
		)
		(pad "12" smd rect
			(at -0.249936 -1.450086 180)
			(size 0.254 0.7112)
			(layers "F.Cu" "F.Mask" "F.Paste")
			(net "P1V8_PCH_AUX")
		)
		(pad "13" smd rect
			(at -0.750062 -1.450086 180)
			(size 0.254 0.7112)
			(layers "F.Cu" "F.Mask" "F.Paste")
			(net "PWRGD_P1V8_PCH_AUX_R")
		)
	)
)
